# SCM (Grand Teton) — schematic netlist excerpt (pin names and nets, part order shuffled) for the footprints in the layout excerpt that follows; sources: Cadence DE-HDL packaged netlist, KiCad conversion of 12092022_DA0F0TMDCD0_F0T_Management_Board_D_brd_V3_OCP.brd

R17  Q_RES  2.21K 1% EMPTY  pkg 0402LF  page 23 : A = V_BMC_LS_DDC_SDA_R ; B = CRT_VCC5
C17  Q_CAP  0.1UF 25V 10% X7R  pkg 0402  page 20 : A = P1V2_AUX ; B = GND

(kicad_pcb
	(version 20260206)
	(generator "pcbnew")
	(generator_version "10.0")
	(general
		(thickness 1.6)
		(legacy_teardrops no)
	)
	(paper "A4")
	(title_block
		(title "12092022_DA0F0TMDCD0_F0T_Management_Board_D_brd_V3_OCP.brd")
		(comment 1 "Grand Teton / footprints 37-38 of 1440")
	)
	(layers
		(0 "F.Cu" signal "TOP")
		(4 "In1.Cu" signal "GND")
		(6 "In2.Cu" signal "IN1")
		(8 "In3.Cu" signal "GND1")
		(10 "In4.Cu" signal "IN2")
		(12 "In5.Cu" signal "VCC")
		(14 "In6.Cu" signal "VCC1")
		(16 "In7.Cu" signal "IN3")
		(18 "In8.Cu" signal "GND2")
		(20 "In9.Cu" signal "IN4")
		(22 "In10.Cu" signal "GND3")
		(2 "B.Cu" signal "BOTTOM")
		(9 "F.Adhes" user "F.Adhesive")
		(11 "B.Adhes" user "B.Adhesive")
		(13 "F.Paste" user "Package Geometry/Pastemask Top")
		(15 "B.Paste" user "Package Geometry/Pastemask Bottom")
		(5 "F.SilkS" user "Ref Des/Silkscreen Top")
		(7 "B.SilkS" user "Ref Des/Silkscreen Bottom")
		(1 "F.Mask" user "Board Geometry/Soldermask Top")
		(3 "B.Mask" user "Board Geometry/Soldermask Bottom")
		(17 "Dwgs.User" user "User.Drawings")
		(19 "Cmts.User" user "User.Comments")
		(21 "Eco1.User" user "User.Eco1")
		(23 "Eco2.User" user "User.Eco2")
		(25 "Edge.Cuts" user "Board Geometry/Outline")
		(27 "Margin" user)
		(31 "F.CrtYd" user "Package Geometry/Place Bound Top")
		(29 "B.CrtYd" user "Package Geometry/Place Bound Bottom")
		(35 "F.Fab" user "Ref Des/Assembly Top")
		(33 "B.Fab" user "Ref Des/Assembly Bottom")
	)
	(footprint ""
		(layer "F.Cu")
		(at 75.25004 -36.298378 180)
		(property "Reference" "C17"
			(at 0 0 180)
			(layer "F.SilkS")
			(hide yes)
			(effects
				(font
					(size 1.27 1.27)
				)
			)
		)
		(property "Value" ""
			(at 0 0 180)
			(layer "F.Fab")
			(effects
				(font
					(size 1.27 1.27)
				)
			)
		)
		(duplicate_pad_numbers_are_jumpers no)
		(fp_line
			(start 0.7874 0.4064)
			(end -0.7874 0.4064)
			(stroke
				(width 0.1524)
				(type default)
			)
			(layer "F.SilkS")
		)
		(fp_line
			(start 0.7874 -0.4064)
			(end 0.7874 0.4064)
			(stroke
				(width 0.1524)
				(type default)
			)
			(layer "F.SilkS")
		)
		(fp_line
			(start -0.7874 0.4064)
			(end -0.7874 -0.4064)
			(stroke
				(width 0.1524)
				(type default)
			)
			(layer "F.SilkS")
		)
		(fp_line
			(start -0.7874 -0.4064)
			(end 0.7874 -0.4064)
			(stroke
				(width 0.1524)
				(type default)
			)
			(layer "F.SilkS")
		)
		(fp_line
			(start 0.67945 0.3048)
			(end 0.120396 0.3048)
			(stroke
				(width 0.1)
				(type default)
			)
			(layer "F.Fab")
		)
		(fp_line
			(start 0.67945 -0.3048)
			(end 0.67945 0.3048)
			(stroke
				(width 0.1)
				(type default)
			)
			(layer "F.Fab")
		)
		(fp_line
			(start 0.12065 -0.2794)
			(end 0.12065 -0.3048)
			(stroke
				(width 0.1)
				(type default)
			)
			(layer "F.Fab")
		)
		(fp_line
			(start 0.12065 -0.3048)
			(end 0.67945 -0.3048)
			(stroke
				(width 0.1)
				(type default)
			)
			(layer "F.Fab")
		)
		(fp_line
			(start 0.120396 0.3048)
			(end 0.120396 0.2794)
			(stroke
				(width 0.1)
				(type default)
			)
			(layer "F.Fab")
		)
		(fp_line
			(start 0.120396 0.2794)
			(end -0.12065 0.2794)
			(stroke
				(width 0.1)
				(type default)
			)
			(layer "F.Fab")
		)
		(fp_line
			(start -0.12065 0.3048)
			(end -0.67945 0.3048)
			(stroke
				(width 0.1)
				(type default)
			)
			(layer "F.Fab")
		)
		(fp_line
			(start -0.12065 0.2794)
			(end -0.12065 0.3048)
			(stroke
				(width 0.1)
				(type default)
			)
			(layer "F.Fab")
		)
		(fp_line
			(start -0.12065 -0.2794)
			(end 0.12065 -0.2794)
			(stroke
				(width 0.1)
				(type default)
			)
			(layer "F.Fab")
		)
		(fp_line
			(start -0.12065 -0.305054)
			(end -0.12065 -0.2794)
			(stroke
				(width 0.1)
				(type default)
			)
			(layer "F.Fab")
		)
		(fp_line
			(start -0.67945 0.3048)
			(end -0.67945 -0.305054)
			(stroke
				(width 0.1)
				(type default)
			)
			(layer "F.Fab")
		)
		(fp_line
			(start -0.67945 -0.305054)
			(end -0.12065 -0.305054)
			(stroke
				(width 0.1)
				(type default)
			)
			(layer "F.Fab")
		)
		(pad "1" smd circle
			(at -0.40005 0 180)
			(size 0 0)
			(layers "F.Cu" "F.Mask" "F.Paste")
			(net "P1V2_AUX")
		)
		(pad "2" smd circle
			(at 0.40005 0 180)
			(size 0 0)
			(layers "F.Cu" "F.Mask" "F.Paste")
			(net "GND")
		)
	)
	(footprint ""
		(layer "F.Cu")
		(at 29.6164 -27.3304 180)
		(property "Reference" "R17"
			(at 0 0 180)
			(layer "F.SilkS")
			(hide yes)
			(effects
				(font
					(size 1.27 1.27)
				)
			)
		)
		(property "Value" ""
			(at 0 0 180)
			(layer "F.Fab")
			(effects
				(font
					(size 1.27 1.27)
				)
			)
		)
		(duplicate_pad_numbers_are_jumpers no)
		(fp_line
			(start 0.7874 0.4064)
			(end -0.7874 0.4064)
			(stroke
				(width 0.1524)
				(type default)
			)
			(layer "F.SilkS")
		)
		(fp_line
			(start 0.7874 -0.4064)
			(end 0.7874 0.4064)
			(stroke
				(width 0.1524)
				(type default)
			)
			(layer "F.SilkS")
		)
		(fp_line
			(start -0.7874 0.4064)
			(end -0.7874 -0.4064)
			(stroke
				(width 0.1524)
				(type default)
			)
			(layer "F.SilkS")
		)
		(fp_line
			(start -0.7874 -0.4064)
			(end 0.7874 -0.4064)
			(stroke
				(width 0.1524)
				(type default)
			)
			(layer "F.SilkS")
		)
		(fp_line
			(start 0.67945 0.3048)
			(end 0.120396 0.3048)
			(stroke
				(width 0.1)
				(type default)
			)
			(layer "F.Fab")
		)
		(fp_line
			(start 0.67945 -0.3048)
			(end 0.67945 0.3048)
			(stroke
				(width 0.1)
				(type default)
			)
			(layer "F.Fab")
		)
		(fp_line
			(start 0.12065 -0.2794)
			(end 0.12065 -0.3048)
			(stroke
				(width 0.1)
				(type default)
			)
			(layer "F.Fab")
		)
		(fp_line
			(start 0.12065 -0.3048)
			(end 0.67945 -0.3048)
			(stroke
				(width 0.1)
				(type default)
			)
			(layer "F.Fab")
		)
		(fp_line
			(start 0.120396 0.3048)
			(end 0.120396 0.2794)
			(stroke
				(width 0.1)
				(type default)
			)
			(layer "F.Fab")
		)
		(fp_line
			(start 0.120396 0.2794)
			(end -0.12065 0.2794)
			(stroke
				(width 0.1)
				(type default)
			)
			(layer "F.Fab")
		)
		(fp_line
			(start -0.12065 0.3048)
			(end -0.67945 0.3048)
			(stroke
				(width 0.1)
				(type default)
			)
			(layer "F.Fab")
		)
		(fp_line
			(start -0.12065 0.2794)
			(end -0.12065 0.3048)
			(stroke
				(width 0.1)
				(type default)
			)
			(layer "F.Fab")
		)
		(fp_line
			(start -0.12065 -0.2794)
			(end 0.12065 -0.2794)
			(stroke
				(width 0.1)
				(type default)
			)
			(layer "F.Fab")
		)
		(fp_line
			(start -0.12065 -0.305054)
			(end -0.12065 -0.2794)
			(stroke
				(width 0.1)
				(type default)
			)
			(layer "F.Fab")
		)
		(fp_line
			(start -0.67945 0.3048)
			(end -0.67945 -0.305054)
			(stroke
				(width 0.1)
				(type default)
			)
			(layer "F.Fab")
		)
		(fp_line
			(start -0.67945 -0.305054)
			(end -0.12065 -0.305054)
			(stroke
				(width 0.1)
				(type default)
			)
			(layer "F.Fab")
		)
		(pad "1" smd circle
			(at -0.40005 0 180)
			(size 0 0)
			(layers "F.Cu" "F.Mask" "F.Paste")
			(net "V_BMC_LS_DDC_SDA_R")
		)
		(pad "2" smd circle
			(at 0.40005 0 180)
			(size 0 0)
			(layers "F.Cu" "F.Mask" "F.Paste")
			(net "CRT_VCC5")
		)
	)
)
